# S9S_MB_2U (Grand Teton) — schematic netlist excerpt (pin names and nets, part order shuffled) for the footprints in the layout excerpt that follows; sources: Cadence DE-HDL packaged netlist, KiCad conversion of 03242023_DA0F0TMBIJ0_F0T_Motherboard_J_brd_V01_OCP.brd

PC1898  Q_CAP  22UF 16V 20% X6S  pkg C0805  page 258 : A = SW_P5V_AUX_FLT ; B = GND
C1822  Q_CAP  0.1UF 25V 10% X7R  pkg 0402  page 161 : A = P3V3_AUX ; B = GND
R4268  Q_RES  0 5% CHIP  pkg 0402LF  page 246 : A = PWRGD_P3V3_AUX_PDB ; B = PWRGD_P3V3_AUX_PDB_R

(kicad_pcb
	(version 20260206)
	(generator "pcbnew")
	(generator_version "10.0")
	(general
		(thickness 1.6)
		(legacy_teardrops no)
	)
	(paper "A4")
	(title_block
		(title "03242023_DA0F0TMBIJ0_F0T_Motherboard_J_brd_V01_OCP.brd")
		(comment 1 "Grand Teton / footprints 3794-3796 of 6105")
	)
	(layers
		(0 "F.Cu" signal "TOP")
		(4 "In1.Cu" signal "GND")
		(6 "In2.Cu" signal "IN1")
		(8 "In3.Cu" signal "GND1")
		(10 "In4.Cu" signal "IN2")
		(12 "In5.Cu" signal "GND2")
		(14 "In6.Cu" signal "IN3")
		(16 "In7.Cu" signal "GND3")
		(18 "In8.Cu" signal "VCC")
		(20 "In9.Cu" signal "VCC1")
		(22 "In10.Cu" signal "GND4")
		(24 "In11.Cu" signal "IN4")
		(26 "In12.Cu" signal "GND5")
		(28 "In13.Cu" signal "IN5")
		(30 "In14.Cu" signal "GND6")
		(32 "In15.Cu" signal "IN6")
		(34 "In16.Cu" signal "GND7")
		(2 "B.Cu" signal "BOTTOM")
		(9 "F.Adhes" user "F.Adhesive")
		(11 "B.Adhes" user "B.Adhesive")
		(13 "F.Paste" user "Package Geometry/Pastemask Top")
		(15 "B.Paste" user "Package Geometry/Pastemask Bottom")
		(5 "F.SilkS" user "Ref Des/Silkscreen Top")
		(7 "B.SilkS" user "Ref Des/Silkscreen Bottom")
		(1 "F.Mask" user "Board Geometry/Soldermask Top")
		(3 "B.Mask" user "Board Geometry/Soldermask Bottom")
		(17 "Dwgs.User" user "User.Drawings")
		(19 "Cmts.User" user "User.Comments")
		(21 "Eco1.User" user "User.Eco1")
		(23 "Eco2.User" user "User.Eco2")
		(25 "Edge.Cuts" user "Board Geometry/Outline")
		(27 "Margin" user)
		(31 "F.CrtYd" user "Package Geometry/Place Bound Top")
		(29 "B.CrtYd" user "Package Geometry/Place Bound Bottom")
		(35 "F.Fab" user "Ref Des/Assembly Top")
		(33 "B.Fab" user "Ref Des/Assembly Bottom")
	)
	(footprint ""
		(layer "F.Cu")
		(at 275.773134 -17.678908 180)
		(property "Reference" "C1822"
			(at 0 0 180)
			(layer "F.SilkS")
			(hide yes)
			(effects
				(font
					(size 1.27 1.27)
				)
			)
		)
		(property "Value" ""
			(at 0 0 180)
			(layer "F.Fab")
			(effects
				(font
					(size 1.27 1.27)
				)
			)
		)
		(duplicate_pad_numbers_are_jumpers no)
		(fp_line
			(start 0.7874 0.4064)
			(end -0.7874 0.4064)
			(stroke
				(width 0.1524)
				(type default)
			)
			(layer "F.SilkS")
		)
		(fp_line
			(start 0.7874 -0.4064)
			(end 0.7874 0.4064)
			(stroke
				(width 0.1524)
				(type default)
			)
			(layer "F.SilkS")
		)
		(fp_line
			(start -0.7874 0.4064)
			(end -0.7874 -0.4064)
			(stroke
				(width 0.1524)
				(type default)
			)
			(layer "F.SilkS")
		)
		(fp_line
			(start -0.7874 -0.4064)
			(end 0.7874 -0.4064)
			(stroke
				(width 0.1524)
				(type default)
			)
			(layer "F.SilkS")
		)
		(fp_line
			(start 0.67945 0.3048)
			(end 0.120396 0.3048)
			(stroke
				(width 0.1)
				(type default)
			)
			(layer "F.Fab")
		)
		(fp_line
			(start 0.67945 -0.3048)
			(end 0.67945 0.3048)
			(stroke
				(width 0.1)
				(type default)
			)
			(layer "F.Fab")
		)
		(fp_line
			(start 0.12065 -0.2794)
			(end 0.12065 -0.3048)
			(stroke
				(width 0.1)
				(type default)
			)
			(layer "F.Fab")
		)
		(fp_line
			(start 0.12065 -0.3048)
			(end 0.67945 -0.3048)
			(stroke
				(width 0.1)
				(type default)
			)
			(layer "F.Fab")
		)
		(fp_line
			(start 0.120396 0.3048)
			(end 0.120396 0.2794)
			(stroke
				(width 0.1)
				(type default)
			)
			(layer "F.Fab")
		)
		(fp_line
			(start 0.120396 0.2794)
			(end -0.12065 0.2794)
			(stroke
				(width 0.1)
				(type default)
			)
			(layer "F.Fab")
		)
		(fp_line
			(start -0.12065 0.3048)
			(end -0.67945 0.3048)
			(stroke
				(width 0.1)
				(type default)
			)
			(layer "F.Fab")
		)
		(fp_line
			(start -0.12065 0.2794)
			(end -0.12065 0.3048)
			(stroke
				(width 0.1)
				(type default)
			)
			(layer "F.Fab")
		)
		(fp_line
			(start -0.12065 -0.2794)
			(end 0.12065 -0.2794)
			(stroke
				(width 0.1)
				(type default)
			)
			(layer "F.Fab")
		)
		(fp_line
			(start -0.12065 -0.305054)
			(end -0.12065 -0.2794)
			(stroke
				(width 0.1)
				(type default)
			)
			(layer "F.Fab")
		)
		(fp_line
			(start -0.67945 0.3048)
			(end -0.67945 -0.305054)
			(stroke
				(width 0.1)
				(type default)
			)
			(layer "F.Fab")
		)
		(fp_line
			(start -0.67945 -0.305054)
			(end -0.12065 -0.305054)
			(stroke
				(width 0.1)
				(type default)
			)
			(layer "F.Fab")
		)
		(pad "1" smd circle
			(at -0.40005 0 180)
			(size 0 0)
			(layers "F.Cu" "F.Mask" "F.Paste")
			(net "P3V3_AUX")
		)
		(pad "2" smd circle
			(at 0.40005 0 180)
			(size 0 0)
			(layers "F.Cu" "F.Mask" "F.Paste")
			(net "GND")
		)
	)
	(footprint ""
		(layer "F.Cu")
		(at 461.463136 -385.742434 90)
		(property "Reference" "PC1898"
			(at 0 0 90)
			(layer "F.SilkS")
			(hide yes)
			(effects
				(font
					(size 1.27 1.27)
				)
			)
		)
		(property "Value" ""
			(at 0 0 90)
			(layer "F.Fab")
			(effects
				(font
					(size 1.27 1.27)
				)
			)
		)
		(duplicate_pad_numbers_are_jumpers no)
		(fp_line
			(start 1.524 -0.762)
			(end 1.524 0.762)
			(stroke
				(width 0.1524)
				(type default)
			)
			(layer "F.SilkS")
		)
		(fp_line
			(start -1.524 -0.762)
			(end 1.524 -0.762)
			(stroke
				(width 0.1524)
				(type default)
			)
			(layer "F.SilkS")
		)
		(fp_line
			(start 1.524 0.762)
			(end -1.524 0.762)
			(stroke
				(width 0.1524)
				(type default)
			)
			(layer "F.SilkS")
		)
		(fp_line
			(start -1.524 0.762)
			(end -1.524 -0.762)
			(stroke
				(width 0.1524)
				(type default)
			)
			(layer "F.SilkS")
		)
		(fp_line
			(start 1.1049 -0.724916)
			(end -1.1049 -0.724916)
			(stroke
				(width 0.1)
				(type default)
			)
			(layer "F.Fab")
		)
		(fp_line
			(start -1.1049 -0.724916)
			(end -1.1049 0.724916)
			(stroke
				(width 0.1)
				(type default)
			)
			(layer "F.Fab")
		)
		(fp_line
			(start 1.1049 0.724916)
			(end 1.1049 -0.724916)
			(stroke
				(width 0.1)
				(type default)
			)
			(layer "F.Fab")
		)
		(fp_line
			(start -1.1049 0.724916)
			(end 1.1049 0.724916)
			(stroke
				(width 0.1)
				(type default)
			)
			(layer "F.Fab")
		)
		(pad "1" smd rect
			(at -0.889 0 270)
			(size 1.016 1.27)
			(layers "F.Cu" "F.Mask" "F.Paste")
			(net "SW_P5V_AUX_FLT")
		)
		(pad "2" smd rect
			(at 0.889 0 270)
			(size 1.016 1.27)
			(layers "F.Cu" "F.Mask" "F.Paste")
			(net "GND")
		)
	)
	(footprint ""
		(layer "F.Cu")
		(at 305.629818 -420.23919 90)
		(property "Reference" "R4268"
			(at 0 0 90)
			(layer "F.SilkS")
			(hide yes)
			(effects
				(font
					(size 1.27 1.27)
				)
			)
		)
		(property "Value" ""
			(at 0 0 90)
			(layer "F.Fab")
			(effects
				(font
					(size 1.27 1.27)
				)
			)
		)
		(duplicate_pad_numbers_are_jumpers no)
		(fp_line
			(start 0.7874 -0.4064)
			(end 0.7874 0.4064)
			(stroke
				(width 0.1524)
				(type default)
			)
			(layer "F.SilkS")
		)
		(fp_line
			(start -0.7874 -0.4064)
			(end 0.7874 -0.4064)
			(stroke
				(width 0.1524)
				(type default)
			)
			(layer "F.SilkS")
		)
		(fp_line
			(start 0.7874 0.4064)
			(end -0.7874 0.4064)
			(stroke
				(width 0.1524)
				(type default)
			)
			(layer "F.SilkS")
		)
		(fp_line
			(start -0.7874 0.4064)
			(end -0.7874 -0.4064)
			(stroke
				(width 0.1524)
				(type default)
			)
			(layer "F.SilkS")
		)
		(fp_line
			(start -0.12065 -0.305054)
			(end -0.12065 -0.2794)
			(stroke
				(width 0.1)
				(type default)
			)
			(layer "F.Fab")
		)
		(fp_line
			(start -0.67945 -0.305054)
			(end -0.12065 -0.305054)
			(stroke
				(width 0.1)
				(type default)
			)
			(layer "F.Fab")
		)
		(fp_line
			(start 0.67945 -0.3048)
			(end 0.67945 0.3048)
			(stroke
				(width 0.1)
				(type default)
			)
			(layer "F.Fab")
		)
		(fp_line
			(start 0.12065 -0.3048)
			(end 0.67945 -0.3048)
			(stroke
				(width 0.1)
				(type default)
			)
			(layer "F.Fab")
		)
		(fp_line
			(start 0.12065 -0.2794)
			(end 0.12065 -0.3048)
			(stroke
				(width 0.1)
				(type default)
			)
			(layer "F.Fab")
		)
		(fp_line
			(start -0.12065 -0.2794)
			(end 0.12065 -0.2794)
			(stroke
				(width 0.1)
				(type default)
			)
			(layer "F.Fab")
		)
		(fp_line
			(start 0.120396 0.2794)
			(end -0.12065 0.2794)
			(stroke
				(width 0.1)
				(type default)
			)
			(layer "F.Fab")
		)
		(fp_line
			(start -0.12065 0.2794)
			(end -0.12065 0.3048)
			(stroke
				(width 0.1)
				(type default)
			)
			(layer "F.Fab")
		)
		(fp_line
			(start 0.67945 0.3048)
			(end 0.120396 0.3048)
			(stroke
				(width 0.1)
				(type default)
			)
			(layer "F.Fab")
		)
		(fp_line
			(start 0.120396 0.3048)
			(end 0.120396 0.2794)
			(stroke
				(width 0.1)
				(type default)
			)
			(layer "F.Fab")
		)
		(fp_line
			(start -0.12065 0.3048)
			(end -0.67945 0.3048)
			(stroke
				(width 0.1)
				(type default)
			)
			(layer "F.Fab")
		)
		(fp_line
			(start -0.67945 0.3048)
			(end -0.67945 -0.305054)
			(stroke
				(width 0.1)
				(type default)
			)
			(layer "F.Fab")
		)
		(pad "1" smd circle
			(at -0.40005 0 90)
			(size 0 0)
			(layers "F.Cu" "F.Mask" "F.Paste")
			(net "PWRGD_P3V3_AUX_PDB")
		)
		(pad "2" smd circle
			(at 0.40005 0 90)
			(size 0 0)
			(layers "F.Cu" "F.Mask" "F.Paste")
			(net "PWRGD_P3V3_AUX_PDB_R")
		)
	)
)
